(kicad_pcb
	(version 20260206)
	(generator "pcbnew")
	(generator_version "10.0")
	(general
		(thickness 1.6)
		(legacy_teardrops no)
	)
	(paper "A4")
	(title_block
		(title "04192023_DAF0TMB3IC0_F0TG_MB_C_brd_V02_OCP.brd")
		(comment 1 "Grand Teton / footprints 8239-8246 of 8354")
	)
	(layers
		(0 "F.Cu" signal "TOP")
		(4 "In1.Cu" signal "GND")
		(6 "In2.Cu" signal "IN1")
		(8 "In3.Cu" signal "GND1")
		(10 "In4.Cu" signal "IN2")
		(12 "In5.Cu" signal "GND2")
		(14 "In6.Cu" signal "IN3")
		(16 "In7.Cu" signal "GND3")
		(18 "In8.Cu" signal "VCC")
		(20 "In9.Cu" signal "VCC1")
		(22 "In10.Cu" signal "GND4")
		(24 "In11.Cu" signal "IN4")
		(26 "In12.Cu" signal "GND5")
		(28 "In13.Cu" signal "IN5")
		(30 "In14.Cu" signal "GND6")
		(32 "In15.Cu" signal "IN6")
		(34 "In16.Cu" signal "GND7")
		(2 "B.Cu" signal "BOTTOM")
		(9 "F.Adhes" user "F.Adhesive")
		(11 "B.Adhes" user "B.Adhesive")
		(13 "F.Paste" user "Package Geometry/Pastemask Top")
		(15 "B.Paste" user "Package Geometry/Pastemask Bottom")
		(5 "F.SilkS" user "Ref Des/Silkscreen Top")
		(7 "B.SilkS" user "Ref Des/Silkscreen Bottom")
		(1 "F.Mask" user "Board Geometry/Soldermask Top")
		(3 "B.Mask" user "Board Geometry/Soldermask Bottom")
		(17 "Dwgs.User" user "User.Drawings")
		(19 "Cmts.User" user "User.Comments")
		(21 "Eco1.User" user "User.Eco1")
		(23 "Eco2.User" user "User.Eco2")
		(25 "Edge.Cuts" user "Board Geometry/Outline")
		(27 "Margin" user)
		(31 "F.CrtYd" user "Package Geometry/Place Bound Top")
		(29 "B.CrtYd" user "Package Geometry/Place Bound Bottom")
		(35 "F.Fab" user "Ref Des/Assembly Top")
		(33 "B.Fab" user "Ref Des/Assembly Bottom")
	)
	(footprint ""
		(layer "B.Cu")
		(at 321.378326 -395.148562 90)
		(property "Reference" "C525"
			(at 0 0 90)
			(layer "B.SilkS")
			(hide yes)
			(effects
				(font
					(size 1.27 1.27)
				)
				(justify mirror)
			)
		)
		(property "Value" ""
			(at 0 0 90)
			(layer "B.Fab")
			(effects
				(font
					(size 1.27 1.27)
				)
				(justify mirror)
			)
		)
		(duplicate_pad_numbers_are_jumpers no)
		(fp_line
			(start 0.299974 -0.150114)
			(end -0.299974 -0.150114)
			(stroke
				(width 0.1)
				(type default)
			)
			(layer "B.Fab")
		)
		(fp_line
			(start -0.299974 -0.150114)
			(end -0.299974 0.150114)
			(stroke
				(width 0.1)
				(type default)
			)
			(layer "B.Fab")
		)
		(fp_line
			(start 0.299974 0.150114)
			(end 0.299974 -0.150114)
			(stroke
				(width 0.1)
				(type default)
			)
			(layer "B.Fab")
		)
		(fp_line
			(start -0.299974 0.150114)
			(end 0.299974 0.150114)
			(stroke
				(width 0.1)
				(type default)
			)
			(layer "B.Fab")
		)
		(pad "1" smd rect
			(at 0.2667 0 270)
			(size 0.3048 0.381)
			(layers "B.Cu" "B.Mask" "B.Paste")
			(net "P0V9_CPU0_RT0_2A")
		)
		(pad "2" smd rect
			(at -0.2667 0 270)
			(size 0.3048 0.381)
			(layers "B.Cu" "B.Mask" "B.Paste")
			(net "GND")
		)
	)
	(footprint ""
		(layer "B.Cu")
		(at 147.146264 -388.011162 -90)
		(property "Reference" "C421"
			(at 0 0 90)
			(layer "B.SilkS")
			(hide yes)
			(effects
				(font
					(size 1.27 1.27)
				)
				(justify mirror)
			)
		)
		(property "Value" ""
			(at 0 0 90)
			(layer "B.Fab")
			(effects
				(font
					(size 1.27 1.27)
				)
				(justify mirror)
			)
		)
		(duplicate_pad_numbers_are_jumpers no)
		(fp_line
			(start -0.299974 0.150114)
			(end 0.299974 0.150114)
			(stroke
				(width 0.1)
				(type default)
			)
			(layer "B.Fab")
		)
		(fp_line
			(start 0.299974 0.150114)
			(end 0.299974 -0.150114)
			(stroke
				(width 0.1)
				(type default)
			)
			(layer "B.Fab")
		)
		(fp_line
			(start -0.299974 -0.150114)
			(end -0.299974 0.150114)
			(stroke
				(width 0.1)
				(type default)
			)
			(layer "B.Fab")
		)
		(fp_line
			(start 0.299974 -0.150114)
			(end -0.299974 -0.150114)
			(stroke
				(width 0.1)
				(type default)
			)
			(layer "B.Fab")
		)
		(pad "1" smd rect
			(at 0.2667 0 90)
			(size 0.3048 0.381)
			(layers "B.Cu" "B.Mask" "B.Paste")
			(net "P0V9_CPU1_RT2_2A")
		)
		(pad "2" smd rect
			(at -0.2667 0 90)
			(size 0.3048 0.381)
			(layers "B.Cu" "B.Mask" "B.Paste")
			(net "GND")
		)
	)
	(footprint ""
		(layer "B.Cu")
		(at 182.499 -145.542 90)
		(property "Reference" "R8036"
			(at 0 0 90)
			(layer "B.SilkS")
			(hide yes)
			(effects
				(font
					(size 1.27 1.27)
				)
				(justify mirror)
			)
		)
		(property "Value" ""
			(at 0 0 90)
			(layer "B.Fab")
			(effects
				(font
					(size 1.27 1.27)
				)
				(justify mirror)
			)
		)
		(duplicate_pad_numbers_are_jumpers no)
		(fp_line
			(start 0.7874 -0.4064)
			(end -0.7874 -0.4064)
			(stroke
				(width 0.1524)
				(type default)
			)
			(layer "B.SilkS")
		)
		(fp_line
			(start -0.7874 -0.4064)
			(end -0.7874 0.4064)
			(stroke
				(width 0.1524)
				(type default)
			)
			(layer "B.SilkS")
		)
		(fp_line
			(start 0.7874 0.4064)
			(end 0.7874 -0.4064)
			(stroke
				(width 0.1524)
				(type default)
			)
			(layer "B.SilkS")
		)
		(fp_line
			(start -0.7874 0.4064)
			(end 0.7874 0.4064)
			(stroke
				(width 0.1524)
				(type default)
			)
			(layer "B.SilkS")
		)
		(fp_line
			(start 0.67945 -0.305054)
			(end 0.12065 -0.305054)
			(stroke
				(width 0.1)
				(type default)
			)
			(layer "B.Fab")
		)
		(fp_line
			(start 0.12065 -0.305054)
			(end 0.12065 -0.2794)
			(stroke
				(width 0.1)
				(type default)
			)
			(layer "B.Fab")
		)
		(fp_line
			(start -0.12065 -0.3048)
			(end -0.67945 -0.3048)
			(stroke
				(width 0.1)
				(type default)
			)
			(layer "B.Fab")
		)
		(fp_line
			(start -0.67945 -0.3048)
			(end -0.67945 0.3048)
			(stroke
				(width 0.1)
				(type default)
			)
			(layer "B.Fab")
		)
		(fp_line
			(start 0.12065 -0.2794)
			(end -0.12065 -0.2794)
			(stroke
				(width 0.1)
				(type default)
			)
			(layer "B.Fab")
		)
		(fp_line
			(start -0.12065 -0.2794)
			(end -0.12065 -0.3048)
			(stroke
				(width 0.1)
				(type default)
			)
			(layer "B.Fab")
		)
		(fp_line
			(start 0.12065 0.2794)
			(end 0.12065 0.3048)
			(stroke
				(width 0.1)
				(type default)
			)
			(layer "B.Fab")
		)
		(fp_line
			(start -0.120396 0.2794)
			(end 0.12065 0.2794)
			(stroke
				(width 0.1)
				(type default)
			)
			(layer "B.Fab")
		)
		(fp_line
			(start 0.67945 0.3048)
			(end 0.67945 -0.305054)
			(stroke
				(width 0.1)
				(type default)
			)
			(layer "B.Fab")
		)
		(fp_line
			(start 0.12065 0.3048)
			(end 0.67945 0.3048)
			(stroke
				(width 0.1)
				(type default)
			)
			(layer "B.Fab")
		)
		(fp_line
			(start -0.120396 0.3048)
			(end -0.120396 0.2794)
			(stroke
				(width 0.1)
				(type default)
			)
			(layer "B.Fab")
		)
		(fp_line
			(start -0.67945 0.3048)
			(end -0.120396 0.3048)
			(stroke
				(width 0.1)
				(type default)
			)
			(layer "B.Fab")
		)
		(pad "1" smd circle
			(at 0.40005 0 270)
			(size 0 0)
			(layers "B.Cu" "B.Mask" "B.Paste")
			(net "PVDD18_S5_P0")
		)
		(pad "2" smd circle
			(at -0.40005 0 270)
			(size 0 0)
			(layers "B.Cu" "B.Mask" "B.Paste")
			(net "ESPI_CPU0_ALERT_PLD_N")
		)
	)
	(footprint ""
		(layer "B.Cu")
		(at 447.237866 -405.7777)
		(property "Reference" "PC6560"
			(at 0 0 0)
			(layer "B.SilkS")
			(hide yes)
			(effects
				(font
					(size 1.27 1.27)
				)
				(justify mirror)
			)
		)
		(property "Value" ""
			(at 0 0 0)
			(layer "B.Fab")
			(effects
				(font
					(size 1.27 1.27)
				)
				(justify mirror)
			)
		)
		(duplicate_pad_numbers_are_jumpers no)
		(fp_line
			(start -1.524 -0.762)
			(end -1.524 0.762)
			(stroke
				(width 0.1524)
				(type default)
			)
			(layer "B.SilkS")
		)
		(fp_line
			(start -1.524 0.762)
			(end 1.524 0.762)
			(stroke
				(width 0.1524)
				(type default)
			)
			(layer "B.SilkS")
		)
		(fp_line
			(start 1.524 -0.762)
			(end -1.524 -0.762)
			(stroke
				(width 0.1524)
				(type default)
			)
			(layer "B.SilkS")
		)
		(fp_line
			(start 1.524 0.762)
			(end 1.524 -0.762)
			(stroke
				(width 0.1524)
				(type default)
			)
			(layer "B.SilkS")
		)
		(fp_line
			(start -1.1049 -0.724916)
			(end 1.1049 -0.724916)
			(stroke
				(width 0.1)
				(type default)
			)
			(layer "B.Fab")
		)
		(fp_line
			(start -1.1049 0.724916)
			(end -1.1049 -0.724916)
			(stroke
				(width 0.1)
				(type default)
			)
			(layer "B.Fab")
		)
		(fp_line
			(start 1.1049 -0.724916)
			(end 1.1049 0.724916)
			(stroke
				(width 0.1)
				(type default)
			)
			(layer "B.Fab")
		)
		(fp_line
			(start 1.1049 0.724916)
			(end -1.1049 0.724916)
			(stroke
				(width 0.1)
				(type default)
			)
			(layer "B.Fab")
		)
		(pad "1" smd rect
			(at 0.889 0)
			(size 1.016 1.27)
			(layers "B.Cu" "B.Mask" "B.Paste")
			(net "SW_P12V_AUX_P0V9_RETIMER_CPU0_FLT")
		)
		(pad "2" smd rect
			(at -0.889 0)
			(size 1.016 1.27)
			(layers "B.Cu" "B.Mask" "B.Paste")
			(net "GND")
		)
	)
	(footprint ""
		(layer "B.Cu")
		(at 365.709454 -264.35431)
		(property "Reference" "C2653"
			(at 0 0 0)
			(layer "B.SilkS")
			(hide yes)
			(effects
				(font
					(size 1.27 1.27)
				)
				(justify mirror)
			)
		)
		(property "Value" ""
			(at 0 0 0)
			(layer "B.Fab")
			(effects
				(font
					(size 1.27 1.27)
				)
				(justify mirror)
			)
		)
		(duplicate_pad_numbers_are_jumpers no)
		(fp_line
			(start -0.7874 -0.4064)
			(end -0.7874 0.4064)
			(stroke
				(width 0.1524)
				(type default)
			)
			(layer "B.SilkS")
		)
		(fp_line
			(start -0.7874 0.4064)
			(end 0.7874 0.4064)
			(stroke
				(width 0.1524)
				(type default)
			)
			(layer "B.SilkS")
		)
		(fp_line
			(start 0.7874 -0.4064)
			(end -0.7874 -0.4064)
			(stroke
				(width 0.1524)
				(type default)
			)
			(layer "B.SilkS")
		)
		(fp_line
			(start 0.7874 0.4064)
			(end 0.7874 -0.4064)
			(stroke
				(width 0.1524)
				(type default)
			)
			(layer "B.SilkS")
		)
		(fp_line
			(start -0.67945 -0.3048)
			(end -0.67945 0.3048)
			(stroke
				(width 0.1)
				(type default)
			)
			(layer "B.Fab")
		)
		(fp_line
			(start -0.67945 0.3048)
			(end -0.120396 0.3048)
			(stroke
				(width 0.1)
				(type default)
			)
			(layer "B.Fab")
		)
		(fp_line
			(start -0.12065 -0.3048)
			(end -0.67945 -0.3048)
			(stroke
				(width 0.1)
				(type default)
			)
			(layer "B.Fab")
		)
		(fp_line
			(start -0.12065 -0.2794)
			(end -0.12065 -0.3048)
			(stroke
				(width 0.1)
				(type default)
			)
			(layer "B.Fab")
		)
		(fp_line
			(start -0.120396 0.2794)
			(end 0.12065 0.2794)
			(stroke
				(width 0.1)
				(type default)
			)
			(layer "B.Fab")
		)
		(fp_line
			(start -0.120396 0.3048)
			(end -0.120396 0.2794)
			(stroke
				(width 0.1)
				(type default)
			)
			(layer "B.Fab")
		)
		(fp_line
			(start 0.12065 -0.305054)
			(end 0.12065 -0.2794)
			(stroke
				(width 0.1)
				(type default)
			)
			(layer "B.Fab")
		)
		(fp_line
			(start 0.12065 -0.2794)
			(end -0.12065 -0.2794)
			(stroke
				(width 0.1)
				(type default)
			)
			(layer "B.Fab")
		)
		(fp_line
			(start 0.12065 0.2794)
			(end 0.12065 0.3048)
			(stroke
				(width 0.1)
				(type default)
			)
			(layer "B.Fab")
		)
		(fp_line
			(start 0.12065 0.3048)
			(end 0.67945 0.3048)
			(stroke
				(width 0.1)
				(type default)
			)
			(layer "B.Fab")
		)
		(fp_line
			(start 0.67945 -0.305054)
			(end 0.12065 -0.305054)
			(stroke
				(width 0.1)
				(type default)
			)
			(layer "B.Fab")
		)
		(fp_line
			(start 0.67945 0.3048)
			(end 0.67945 -0.305054)
			(stroke
				(width 0.1)
				(type default)
			)
			(layer "B.Fab")
		)
		(pad "1" smd circle
			(at 0.40005 0 180)
			(size 0 0)
			(layers "B.Cu" "B.Mask" "B.Paste")
			(net "PVDD11_S3_P0")
		)
		(pad "2" smd circle
			(at -0.40005 0 180)
			(size 0 0)
			(layers "B.Cu" "B.Mask" "B.Paste")
			(net "GND")
		)
	)
	(footprint ""
		(layer "B.Cu")
		(at 435.000146 -192.660016 180)
		(property "Reference" "C165"
			(at 0 0 0)
			(layer "B.SilkS")
			(hide yes)
			(effects
				(font
					(size 1.27 1.27)
				)
				(justify mirror)
			)
		)
		(property "Value" ""
			(at 0 0 0)
			(layer "B.Fab")
			(effects
				(font
					(size 1.27 1.27)
				)
				(justify mirror)
			)
		)
		(duplicate_pad_numbers_are_jumpers no)
		(fp_line
			(start 1.524 0.762)
			(end 1.524 -0.762)
			(stroke
				(width 0.1524)
				(type default)
			)
			(layer "B.SilkS")
		)
		(fp_line
			(start 1.524 -0.762)
			(end -1.524 -0.762)
			(stroke
				(width 0.1524)
				(type default)
			)
			(layer "B.SilkS")
		)
		(fp_line
			(start -1.524 0.762)
			(end 1.524 0.762)
			(stroke
				(width 0.1524)
				(type default)
			)
			(layer "B.SilkS")
		)
		(fp_line
			(start -1.524 -0.762)
			(end -1.524 0.762)
			(stroke
				(width 0.1524)
				(type default)
			)
			(layer "B.SilkS")
		)
		(fp_line
			(start 1.1049 0.724916)
			(end -1.1049 0.724916)
			(stroke
				(width 0.1)
				(type default)
			)
			(layer "B.Fab")
		)
		(fp_line
			(start 1.1049 -0.724916)
			(end 1.1049 0.724916)
			(stroke
				(width 0.1)
				(type default)
			)
			(layer "B.Fab")
		)
		(fp_line
			(start -1.1049 0.724916)
			(end -1.1049 -0.724916)
			(stroke
				(width 0.1)
				(type default)
			)
			(layer "B.Fab")
		)
		(fp_line
			(start -1.1049 -0.724916)
			(end 1.1049 -0.724916)
			(stroke
				(width 0.1)
				(type default)
			)
			(layer "B.Fab")
		)
		(pad "1" smd rect
			(at 0.889 0 180)
			(size 1.016 1.27)
			(layers "B.Cu" "B.Mask" "B.Paste")
			(net "P12V_MEM_CPU0")
		)
		(pad "2" smd rect
			(at -0.889 0 180)
			(size 1.016 1.27)
			(layers "B.Cu" "B.Mask" "B.Paste")
			(net "GND")
		)
	)
	(footprint ""
		(layer "B.Cu")
		(at 22.479 -362.204 180)
		(property "Reference" "C5006"
			(at 0 0 0)
			(layer "B.SilkS")
			(hide yes)
			(effects
				(font
					(size 1.27 1.27)
				)
				(justify mirror)
			)
		)
		(property "Value" ""
			(at 0 0 0)
			(layer "B.Fab")
			(effects
				(font
					(size 1.27 1.27)
				)
				(justify mirror)
			)
		)
		(duplicate_pad_numbers_are_jumpers no)
		(fp_line
			(start 0.7874 0.4064)
			(end 0.7874 -0.4064)
			(stroke
				(width 0.1524)
				(type default)
			)
			(layer "B.SilkS")
		)
		(fp_line
			(start 0.7874 -0.4064)
			(end -0.7874 -0.4064)
			(stroke
				(width 0.1524)
				(type default)
			)
			(layer "B.SilkS")
		)
		(fp_line
			(start -0.7874 0.4064)
			(end 0.7874 0.4064)
			(stroke
				(width 0.1524)
				(type default)
			)
			(layer "B.SilkS")
		)
		(fp_line
			(start -0.7874 -0.4064)
			(end -0.7874 0.4064)
			(stroke
				(width 0.1524)
				(type default)
			)
			(layer "B.SilkS")
		)
		(fp_line
			(start 0.67945 0.3048)
			(end 0.67945 -0.305054)
			(stroke
				(width 0.1)
				(type default)
			)
			(layer "B.Fab")
		)
		(fp_line
			(start 0.67945 -0.305054)
			(end 0.12065 -0.305054)
			(stroke
				(width 0.1)
				(type default)
			)
			(layer "B.Fab")
		)
		(fp_line
			(start 0.12065 0.3048)
			(end 0.67945 0.3048)
			(stroke
				(width 0.1)
				(type default)
			)
			(layer "B.Fab")
		)
		(fp_line
			(start 0.12065 0.2794)
			(end 0.12065 0.3048)
			(stroke
				(width 0.1)
				(type default)
			)
			(layer "B.Fab")
		)
		(fp_line
			(start 0.12065 -0.2794)
			(end -0.12065 -0.2794)
			(stroke
				(width 0.1)
				(type default)
			)
			(layer "B.Fab")
		)
		(fp_line
			(start 0.12065 -0.305054)
			(end 0.12065 -0.2794)
			(stroke
				(width 0.1)
				(type default)
			)
			(layer "B.Fab")
		)
		(fp_line
			(start -0.120396 0.3048)
			(end -0.120396 0.2794)
			(stroke
				(width 0.1)
				(type default)
			)
			(layer "B.Fab")
		)
		(fp_line
			(start -0.120396 0.2794)
			(end 0.12065 0.2794)
			(stroke
				(width 0.1)
				(type default)
			)
			(layer "B.Fab")
		)
		(fp_line
			(start -0.12065 -0.2794)
			(end -0.12065 -0.3048)
			(stroke
				(width 0.1)
				(type default)
			)
			(layer "B.Fab")
		)
		(fp_line
			(start -0.12065 -0.3048)
			(end -0.67945 -0.3048)
			(stroke
				(width 0.1)
				(type default)
			)
			(layer "B.Fab")
		)
		(fp_line
			(start -0.67945 0.3048)
			(end -0.120396 0.3048)
			(stroke
				(width 0.1)
				(type default)
			)
			(layer "B.Fab")
		)
		(fp_line
			(start -0.67945 -0.3048)
			(end -0.67945 0.3048)
			(stroke
				(width 0.1)
				(type default)
			)
			(layer "B.Fab")
		)
		(pad "1" smd circle
			(at 0.40005 0)
			(size 0 0)
			(layers "B.Cu" "B.Mask" "B.Paste")
			(net "GND")
		)
		(pad "2" smd circle
			(at -0.40005 0)
			(size 0 0)
			(layers "B.Cu" "B.Mask" "B.Paste")
			(net "PWRGD_PVDDIO_P1")
		)
	)
	(footprint ""
		(layer "B.Cu")
		(at 40.9956 -194.885564 180)
		(property "Reference" "R771"
			(at 0 0 0)
			(layer "B.SilkS")
			(hide yes)
			(effects
				(font
					(size 1.27 1.27)
				)
				(justify mirror)
			)
		)
		(property "Value" ""
			(at 0 0 0)
			(layer "B.Fab")
			(effects
				(font
					(size 1.27 1.27)
				)
				(justify mirror)
			)
		)
		(duplicate_pad_numbers_are_jumpers no)
		(fp_line
			(start 0.7874 0.4064)
			(end 0.7874 -0.4064)
			(stroke
				(width 0.1524)
				(type default)
			)
			(layer "B.SilkS")
		)
		(fp_line
			(start 0.7874 -0.4064)
			(end -0.7874 -0.4064)
			(stroke
				(width 0.1524)
				(type default)
			)
			(layer "B.SilkS")
		)
		(fp_line
			(start -0.7874 0.4064)
			(end 0.7874 0.4064)
			(stroke
				(width 0.1524)
				(type default)
			)
			(layer "B.SilkS")
		)
		(fp_line
			(start -0.7874 -0.4064)
			(end -0.7874 0.4064)
			(stroke
				(width 0.1524)
				(type default)
			)
			(layer "B.SilkS")
		)
		(fp_line
			(start 0.67945 0.3048)
			(end 0.67945 -0.305054)
			(stroke
				(width 0.1)
				(type default)
			)
			(layer "B.Fab")
		)
		(fp_line
			(start 0.67945 -0.305054)
			(end 0.12065 -0.305054)
			(stroke
				(width 0.1)
				(type default)
			)
			(layer "B.Fab")
		)
		(fp_line
			(start 0.12065 0.3048)
			(end 0.67945 0.3048)
			(stroke
				(width 0.1)
				(type default)
			)
			(layer "B.Fab")
		)
		(fp_line
			(start 0.12065 0.2794)
			(end 0.12065 0.3048)
			(stroke
				(width 0.1)
				(type default)
			)
			(layer "B.Fab")
		)
		(fp_line
			(start 0.12065 -0.2794)
			(end -0.12065 -0.2794)
			(stroke
				(width 0.1)
				(type default)
			)
			(layer "B.Fab")
		)
		(fp_line
			(start 0.12065 -0.305054)
			(end 0.12065 -0.2794)
			(stroke
				(width 0.1)
				(type default)
			)
			(layer "B.Fab")
		)
		(fp_line
			(start -0.120396 0.3048)
			(end -0.120396 0.2794)
			(stroke
				(width 0.1)
				(type default)
			)
			(layer "B.Fab")
		)
		(fp_line
			(start -0.120396 0.2794)
			(end 0.12065 0.2794)
			(stroke
				(width 0.1)
				(type default)
			)
			(layer "B.Fab")
		)
		(fp_line
			(start -0.12065 -0.2794)
			(end -0.12065 -0.3048)
			(stroke
				(width 0.1)
				(type default)
			)
			(layer "B.Fab")
		)
		(fp_line
			(start -0.12065 -0.3048)
			(end -0.67945 -0.3048)
			(stroke
				(width 0.1)
				(type default)
			)
			(layer "B.Fab")
		)
		(fp_line
			(start -0.67945 0.3048)
			(end -0.120396 0.3048)
			(stroke
				(width 0.1)
				(type default)
			)
			(layer "B.Fab")
		)
		(fp_line
			(start -0.67945 -0.3048)
			(end -0.67945 0.3048)
			(stroke
				(width 0.1)
				(type default)
			)
			(layer "B.Fab")
		)
		(pad "1" smd circle
			(at 0.40005 0)
			(size 0 0)
			(layers "B.Cu" "B.Mask" "B.Paste")
			(net "PD_CHC_CPU1_DIMM_SAA")
		)
		(pad "2" smd circle
			(at -0.40005 0)
			(size 0 0)
			(layers "B.Cu" "B.Mask" "B.Paste")
			(net "GND")
		)
	)
)
